(kicad_pcb
	(version 20241229)
	(generator "pcbnew")
	(generator_version "9.0")
	(general
		(thickness 1.599998)
		(legacy_teardrops no)
	)
	(paper "A4")
	(title_block
		(title "Artix - Datacenter Secure Control Module (DC-SCM)")
		(date "2024-11-06")
		(rev "1.1.3")
		(comment 9 "footprints 123-127 of 544")
	)
	(layers
		(0 "F.Cu" signal)
		(4 "In1.Cu" signal)
		(6 "In2.Cu" signal)
		(8 "In3.Cu" signal)
		(10 "In4.Cu" signal)
		(12 "In5.Cu" signal)
		(14 "In6.Cu" signal)
		(2 "B.Cu" signal)
		(9 "F.Adhes" user "F.Adhesive")
		(11 "B.Adhes" user "B.Adhesive")
		(13 "F.Paste" user)
		(15 "B.Paste" user)
		(5 "F.SilkS" user "F.Silkscreen")
		(7 "B.SilkS" user "B.Silkscreen")
		(1 "F.Mask" user)
		(3 "B.Mask" user)
		(17 "Dwgs.User" user "User.Drawings")
		(19 "Cmts.User" user "User.Comments")
		(21 "Eco1.User" user "User.Eco1")
		(23 "Eco2.User" user "User.Eco2")
		(25 "Edge.Cuts" user)
		(27 "Margin" user)
		(31 "F.CrtYd" user "F.Courtyard")
		(29 "B.CrtYd" user "B.Courtyard")
		(35 "F.Fab" user)
		(33 "B.Fab" user)
	)
	(footprint "antmicro-footprints:R_0402_1005Metric"
		(layer "F.Cu")
		(at 143.05 63.705 -90)
		(descr "Resistor SMD 0402")
		(tags "resistor SMD 0402")
		(property "Reference" "R132"
			(at -1.105 -3.85 90)
			(layer "F.SilkS")
			(effects
				(font
					(size 0.7 0.7)
					(thickness 0.15)
				)
				(justify right bottom)
			)
		)
		(property "Value" "R_1k_0402"
			(at 0 1.4 90)
			(layer "F.Fab")
			(effects
				(font
					(size 0.7 0.7)
					(thickness 0.15)
				)
				(justify right bottom)
			)
		)
		(property "Datasheet" "https://www.bourns.com/docs/product-datasheets/cr.pdf"
			(at 0 0 270)
			(layer "F.Fab")
			(hide yes)
			(effects
				(font
					(size 1.27 1.27)
					(thickness 0.15)
				)
			)
		)
		(property "Description" "SMD Chip Resistor, 1 kohm, ± 1%, 63 mW, 0402 [1005 Metric], Thick Film, General Purpose"
			(at 0 0 270)
			(layer "F.Fab")
			(hide yes)
			(effects
				(font
					(size 1.27 1.27)
					(thickness 0.15)
				)
			)
		)
		(property "Author" "Antmicro"
			(at 79.345 206.755 0)
			(layer "F.Fab")
			(hide yes)
			(effects
				(font
					(size 1 1)
					(thickness 0.15)
				)
			)
		)
		(property "License" "Apache-2.0"
			(at 79.345 206.755 0)
			(layer "F.Fab")
			(hide yes)
			(effects
				(font
					(size 1 1)
					(thickness 0.15)
				)
			)
		)
		(property "MPN" "CR0402-FX-1001GLF"
			(at 79.345 206.755 0)
			(layer "F.Fab")
			(hide yes)
			(effects
				(font
					(size 1 1)
					(thickness 0.15)
				)
			)
		)
		(property "Manufacturer" "Bourns"
			(at 79.345 206.755 0)
			(layer "F.Fab")
			(hide yes)
			(effects
				(font
					(size 1 1)
					(thickness 0.15)
				)
			)
		)
		(property "Tolerance" "1%"
			(at 79.345 206.755 0)
			(layer "F.Fab")
			(hide yes)
			(effects
				(font
					(size 1 1)
					(thickness 0.15)
				)
			)
		)
		(property "Val" "1k"
			(at 79.345 206.755 0)
			(layer "F.Fab")
			(hide yes)
			(effects
				(font
					(size 1 1)
					(thickness 0.15)
				)
			)
		)
		(sheetname "/FPGA banks 34-35 & CFG/")
		(sheetfile "fpga-banks-34-25-cfg.kicad_sch")
		(attr smd)
		(fp_rect
			(start -0.925 -0.47)
			(end 0.925 0.47)
			(stroke
				(width 0.05)
				(type default)
			)
			(fill no)
			(layer "F.CrtYd")
		)
		(fp_rect
			(start -0.5 -0.25)
			(end 0.5 0.25)
			(stroke
				(width 0.15)
				(type solid)
			)
			(fill no)
			(layer "F.Fab")
		)
		(pad "1" smd roundrect
			(at -0.48 0 270)
			(size 0.59 0.64)
			(layers "F.Cu" "F.Mask" "F.Paste")
			(roundrect_rratio 0.25)
			(net 311 "Net-(D13-A)")
			(pintype "passive")
		)
		(pad "2" smd roundrect
			(at 0.48 0 270)
			(size 0.59 0.64)
			(layers "F.Cu" "F.Mask" "F.Paste")
			(roundrect_rratio 0.25)
			(net 2 "VCC3V3")
			(pintype "passive")
		)
	)
	(footprint "antmicro-footprints:SOIC-8_5.3x5.3x2mm_P1.27mm"
		(layer "F.Cu")
		(at 66.5 118.605 90)
		(descr "8-Pin SOIC 208-mil")
		(property "Reference" "U2"
			(at -0.0015 -3.2 90)
			(layer "F.SilkS")
			(effects
				(font
					(size 0.7 0.7)
					(thickness 0.15)
				)
				(justify left bottom)
			)
		)
		(property "Value" "W25Q32JW_SOIC-8"
			(at 0 3.8 90)
			(layer "F.Fab")
			(effects
				(font
					(size 0.7 0.7)
					(thickness 0.15)
				)
				(justify left bottom)
			)
		)
		(property "Datasheet" "https://www.mouser.com/datasheet/2/949/w25q32jw_spi_revf_09042018-1489621.pdf"
			(at 0 0 90)
			(layer "F.Fab")
			(hide yes)
			(effects
				(font
					(size 1.27 1.27)
					(thickness 0.15)
				)
			)
		)
		(property "Description" "FLASH - NOR Memory IC 32Mbit SPI - Quad I/O 133 MHz 8-SOIC"
			(at 0 0 90)
			(layer "F.Fab")
			(hide yes)
			(effects
				(font
					(size 1.27 1.27)
					(thickness 0.15)
				)
			)
		)
		(property "Author" "Antmicro"
			(at 185.105 52.105 0)
			(layer "F.Fab")
			(hide yes)
			(effects
				(font
					(size 1 1)
					(thickness 0.15)
				)
			)
		)
		(property "License" "Apache-2.0"
			(at 185.105 52.105 0)
			(layer "F.Fab")
			(hide yes)
			(effects
				(font
					(size 1 1)
					(thickness 0.15)
				)
			)
		)
		(property "MPN" "W25Q32JWSSIQ"
			(at 185.105 52.105 0)
			(layer "F.Fab")
			(hide yes)
			(effects
				(font
					(size 1 1)
					(thickness 0.15)
				)
			)
		)
		(property "Manufacturer" "Winbond"
			(at 185.105 52.105 0)
			(layer "F.Fab")
			(hide yes)
			(effects
				(font
					(size 1 1)
					(thickness 0.15)
				)
			)
		)
		(sheetname "/RoT/")
		(sheetfile "rot.kicad_sch")
		(attr smd)
		(fp_line
			(start -2.8 -2.641)
			(end -4.4 -2.641)
			(stroke
				(width 0.15)
				(type solid)
			)
			(layer "F.SilkS")
		)
		(fp_circle
			(center -4.85 -1.905)
			(end -4.8 -1.855)
			(stroke
				(width 0.15)
				(type solid)
			)
			(fill yes)
			(layer "F.SilkS")
		)
		(fp_rect
			(start 4.675 -3)
			(end -4.675 3)
			(stroke
				(width 0.05)
				(type solid)
			)
			(fill no)
			(layer "F.CrtYd")
		)
		(fp_line
			(start 2.64 -2.641)
			(end 2.64 2.64)
			(stroke
				(width 0.15)
				(type solid)
			)
			(layer "F.Fab")
		)
		(fp_line
			(start -2.641 -2.641)
			(end 2.64 -2.641)
			(stroke
				(width 0.15)
				(type solid)
			)
			(layer "F.Fab")
		)
		(fp_line
			(start -2.641 -1.371)
			(end -1.371 -2.641)
			(stroke
				(width 0.15)
				(type solid)
			)
			(layer "F.Fab")
		)
		(fp_line
			(start 2.64 2.64)
			(end -2.641 2.64)
			(stroke
				(width 0.15)
				(type solid)
			)
			(layer "F.Fab")
		)
		(fp_line
			(start -2.641 2.64)
			(end -2.641 -2.641)
			(stroke
				(width 0.15)
				(type solid)
			)
			(layer "F.Fab")
		)
		(pad "1" smd roundrect
			(at -3.601 -1.905 180)
			(size 0.65 1.65)
			(layers "F.Cu" "F.Mask" "F.Paste")
			(roundrect_rratio 0.25)
			(net 129 "QSPIB2_CS_N")
			(pinfunction "~{CS}")
			(pintype "input")
		)
		(pad "2" smd roundrect
			(at -3.601 -0.635 180)
			(size 0.65 1.65)
			(layers "F.Cu" "F.Mask" "F.Paste")
			(roundrect_rratio 0.25)
			(net 126 "QSPIB2_D1")
			(pinfunction "SO/IO1")
			(pintype "bidirectional")
		)
		(pad "3" smd roundrect
			(at -3.601 0.633 180)
			(size 0.65 1.65)
			(layers "F.Cu" "F.Mask" "F.Paste")
			(roundrect_rratio 0.25)
			(net 127 "QSPIB2_D2")
			(pinfunction "~{WP}/IO2")
			(pintype "bidirectional")
		)
		(pad "4" smd roundrect
			(at -3.601 1.904 180)
			(size 0.65 1.65)
			(layers "F.Cu" "F.Mask" "F.Paste")
			(roundrect_rratio 0.25)
			(net 1 "GND")
			(pinfunction "VSS")
			(pintype "power_in")
		)
		(pad "5" smd roundrect
			(at 3.6 1.904 180)
			(size 0.65 1.65)
			(layers "F.Cu" "F.Mask" "F.Paste")
			(roundrect_rratio 0.25)
			(net 125 "QSPIB2_D0")
			(pinfunction "SI/IO0")
			(pintype "bidirectional")
		)
		(pad "6" smd roundrect
			(at 3.6 0.633 180)
			(size 0.65 1.65)
			(layers "F.Cu" "F.Mask" "F.Paste")
			(roundrect_rratio 0.25)
			(net 119 "QSPIB_CLK")
			(pinfunction "SCLK")
			(pintype "input")
		)
		(pad "7" smd roundrect
			(at 3.6 -0.635 180)
			(size 0.65 1.65)
			(layers "F.Cu" "F.Mask" "F.Paste")
			(roundrect_rratio 0.25)
			(net 128 "QSPIB2_D3")
			(pinfunction "~{HOLD}/IO3")
			(pintype "bidirectional")
		)
		(pad "8" smd roundrect
			(at 3.6 -1.905 180)
			(size 0.65 1.65)
			(layers "F.Cu" "F.Mask" "F.Paste")
			(roundrect_rratio 0.25)
			(net 2 "VCC3V3")
			(pinfunction "VCC")
			(pintype "power_in")
		)
	)
	(footprint "antmicro-footprints:SOIC-8_5.3x5.3x2mm_P1.27mm"
		(layer "F.Cu")
		(at 66.46 128.155 90)
		(descr "8-Pin SOIC 208-mil")
		(property "Reference" "U3"
			(at -0.0015 -3.2 90)
			(layer "F.SilkS")
			(effects
				(font
					(size 0.7 0.7)
					(thickness 0.15)
				)
				(justify left bottom)
			)
		)
		(property "Value" "W25Q32JW_SOIC-8"
			(at 0 3.8 90)
			(layer "F.Fab")
			(effects
				(font
					(size 0.7 0.7)
					(thickness 0.15)
				)
				(justify left bottom)
			)
		)
		(property "Datasheet" "https://www.mouser.com/datasheet/2/949/w25q32jw_spi_revf_09042018-1489621.pdf"
			(at 0 0 90)
			(layer "F.Fab")
			(hide yes)
			(effects
				(font
					(size 1.27 1.27)
					(thickness 0.15)
				)
			)
		)
		(property "Description" "FLASH - NOR Memory IC 32Mbit SPI - Quad I/O 133 MHz 8-SOIC"
			(at 0 0 90)
			(layer "F.Fab")
			(hide yes)
			(effects
				(font
					(size 1.27 1.27)
					(thickness 0.15)
				)
			)
		)
		(property "Author" "Antmicro"
			(at 194.615 61.695 0)
			(layer "F.Fab")
			(hide yes)
			(effects
				(font
					(size 1 1)
					(thickness 0.15)
				)
			)
		)
		(property "License" "Apache-2.0"
			(at 194.615 61.695 0)
			(layer "F.Fab")
			(hide yes)
			(effects
				(font
					(size 1 1)
					(thickness 0.15)
				)
			)
		)
		(property "MPN" "W25Q32JWSSIQ"
			(at 194.615 61.695 0)
			(layer "F.Fab")
			(hide yes)
			(effects
				(font
					(size 1 1)
					(thickness 0.15)
				)
			)
		)
		(property "Manufacturer" "Winbond"
			(at 194.615 61.695 0)
			(layer "F.Fab")
			(hide yes)
			(effects
				(font
					(size 1 1)
					(thickness 0.15)
				)
			)
		)
		(sheetname "/RoT/")
		(sheetfile "rot.kicad_sch")
		(attr smd)
		(fp_line
			(start -2.8 -2.641)
			(end -4.4 -2.641)
			(stroke
				(width 0.15)
				(type solid)
			)
			(layer "F.SilkS")
		)
		(fp_circle
			(center -4.85 -1.905)
			(end -4.8 -1.855)
			(stroke
				(width 0.15)
				(type solid)
			)
			(fill yes)
			(layer "F.SilkS")
		)
		(fp_rect
			(start 4.675 -3)
			(end -4.675 3)
			(stroke
				(width 0.05)
				(type solid)
			)
			(fill no)
			(layer "F.CrtYd")
		)
		(fp_line
			(start 2.64 -2.641)
			(end 2.64 2.64)
			(stroke
				(width 0.15)
				(type solid)
			)
			(layer "F.Fab")
		)
		(fp_line
			(start -2.641 -2.641)
			(end 2.64 -2.641)
			(stroke
				(width 0.15)
				(type solid)
			)
			(layer "F.Fab")
		)
		(fp_line
			(start -2.641 -1.371)
			(end -1.371 -2.641)
			(stroke
				(width 0.15)
				(type solid)
			)
			(layer "F.Fab")
		)
		(fp_line
			(start 2.64 2.64)
			(end -2.641 2.64)
			(stroke
				(width 0.15)
				(type solid)
			)
			(layer "F.Fab")
		)
		(fp_line
			(start -2.641 2.64)
			(end -2.641 -2.641)
			(stroke
				(width 0.15)
				(type solid)
			)
			(layer "F.Fab")
		)
		(pad "1" smd roundrect
			(at -3.601 -1.905 180)
			(size 0.65 1.65)
			(layers "F.Cu" "F.Mask" "F.Paste")
			(roundrect_rratio 0.25)
			(net 124 "QSPIB1_CS_N")
			(pinfunction "~{CS}")
			(pintype "input")
		)
		(pad "2" smd roundrect
			(at -3.601 -0.635 180)
			(size 0.65 1.65)
			(layers "F.Cu" "F.Mask" "F.Paste")
			(roundrect_rratio 0.25)
			(net 121 "QSPIB1_D1")
			(pinfunction "SO/IO1")
			(pintype "bidirectional")
		)
		(pad "3" smd roundrect
			(at -3.601 0.633 180)
			(size 0.65 1.65)
			(layers "F.Cu" "F.Mask" "F.Paste")
			(roundrect_rratio 0.25)
			(net 122 "QSPIB1_D2")
			(pinfunction "~{WP}/IO2")
			(pintype "bidirectional")
		)
		(pad "4" smd roundrect
			(at -3.601 1.904 180)
			(size 0.65 1.65)
			(layers "F.Cu" "F.Mask" "F.Paste")
			(roundrect_rratio 0.25)
			(net 1 "GND")
			(pinfunction "VSS")
			(pintype "power_in")
		)
		(pad "5" smd roundrect
			(at 3.6 1.904 180)
			(size 0.65 1.65)
			(layers "F.Cu" "F.Mask" "F.Paste")
			(roundrect_rratio 0.25)
			(net 120 "QSPIB1_D0")
			(pinfunction "SI/IO0")
			(pintype "bidirectional")
		)
		(pad "6" smd roundrect
			(at 3.6 0.633 180)
			(size 0.65 1.65)
			(layers "F.Cu" "F.Mask" "F.Paste")
			(roundrect_rratio 0.25)
			(net 119 "QSPIB_CLK")
			(pinfunction "SCLK")
			(pintype "input")
		)
		(pad "7" smd roundrect
			(at 3.6 -0.635 180)
			(size 0.65 1.65)
			(layers "F.Cu" "F.Mask" "F.Paste")
			(roundrect_rratio 0.25)
			(net 123 "QSPIB1_D3")
			(pinfunction "~{HOLD}/IO3")
			(pintype "bidirectional")
		)
		(pad "8" smd roundrect
			(at 3.6 -1.905 180)
			(size 0.65 1.65)
			(layers "F.Cu" "F.Mask" "F.Paste")
			(roundrect_rratio 0.25)
			(net 2 "VCC3V3")
			(pinfunction "VCC")
			(pintype "power_in")
		)
	)
	(footprint "antmicro-footprints:C_0402_1005Metric"
		(layer "F.Cu")
		(at 105.275 162.075 180)
		(descr "Capacitor SMD 0402")
		(tags "capacitor SMD 0402")
		(property "Reference" "C42"
			(at -3.025 -0.325 0)
			(layer "F.SilkS")
			(effects
				(font
					(size 0.7 0.7)
					(thickness 0.15)
				)
				(justify right bottom)
			)
		)
		(property "Value" "C_100n_6V3_0402"
			(at 0 1.4 0)
			(layer "F.Fab")
			(effects
				(font
					(size 0.7 0.7)
					(thickness 0.15)
				)
				(justify right bottom)
			)
		)
		(property "Datasheet" "https://www.passivecomponent.com/wp-content/uploads/datasheet/WTC_MLCC_General_Purpose.pdf"
			(at 0 0 180)
			(layer "F.Fab")
			(hide yes)
			(effects
				(font
					(size 1.27 1.27)
					(thickness 0.15)
				)
			)
		)
		(property "Description" "SMT Multilayer Ceramic Capacitor, 0.1 µF, 6.3 V, 0402 [1005 Metric], ± 10%, X5R, Walsin MLCC"
			(at 0 0 180)
			(layer "F.Fab")
			(hide yes)
			(effects
				(font
					(size 1.27 1.27)
					(thickness 0.15)
				)
			)
		)
		(property "Author" "Antmicro"
			(at 210.55 324.15 0)
			(layer "F.Fab")
			(hide yes)
			(effects
				(font
					(size 1 1)
					(thickness 0.15)
				)
			)
		)
		(property "Dielectric" ""
			(at 210.55 324.15 0)
			(layer "F.Fab")
			(hide yes)
			(effects
				(font
					(size 1 1)
					(thickness 0.15)
				)
			)
		)
		(property "License" "Apache-2.0"
			(at 210.55 324.15 0)
			(layer "F.Fab")
			(hide yes)
			(effects
				(font
					(size 1 1)
					(thickness 0.15)
				)
			)
		)
		(property "MPN" "0402X104K6R3CT"
			(at 210.55 324.15 0)
			(layer "F.Fab")
			(hide yes)
			(effects
				(font
					(size 1 1)
					(thickness 0.15)
				)
			)
		)
		(property "Manufacturer" "Walsin"
			(at 210.55 324.15 0)
			(layer "F.Fab")
			(hide yes)
			(effects
				(font
					(size 1 1)
					(thickness 0.15)
				)
			)
		)
		(property "Public" "False"
			(at 210.55 324.15 0)
			(layer "F.Fab")
			(hide yes)
			(effects
				(font
					(size 1 1)
					(thickness 0.15)
				)
			)
		)
		(property "Val" "100n"
			(at 210.55 324.15 0)
			(layer "F.Fab")
			(hide yes)
			(effects
				(font
					(size 1 1)
					(thickness 0.15)
				)
			)
		)
		(property "Voltage" ""
			(at 210.55 324.15 0)
			(layer "F.Fab")
			(hide yes)
			(effects
				(font
					(size 1 1)
					(thickness 0.15)
				)
			)
		)
		(sheetname "/DDR3/")
		(sheetfile "ddr3.kicad_sch")
		(attr smd)
		(fp_rect
			(start -0.925 -0.47)
			(end 0.925 0.47)
			(stroke
				(width 0.05)
				(type default)
			)
			(fill no)
			(layer "F.CrtYd")
		)
		(fp_line
			(start 0.504 0.248)
			(end -0.494 0.248)
			(stroke
				(width 0.15)
				(type solid)
			)
			(layer "F.Fab")
		)
		(fp_line
			(start 0.504 -0.25)
			(end 0.504 0.248)
			(stroke
				(width 0.15)
				(type solid)
			)
			(layer "F.Fab")
		)
		(fp_line
			(start -0.494 0.248)
			(end -0.494 -0.25)
			(stroke
				(width 0.15)
				(type solid)
			)
			(layer "F.Fab")
		)
		(fp_line
			(start -0.494 -0.25)
			(end 0.504 -0.25)
			(stroke
				(width 0.15)
				(type solid)
			)
			(layer "F.Fab")
		)
		(pad "1" smd roundrect
			(at -0.48 0 180)
			(size 0.59 0.64)
			(layers "F.Cu" "F.Mask" "F.Paste")
			(roundrect_rratio 0.25)
			(net 1 "GND")
			(pintype "passive")
		)
		(pad "2" smd roundrect
			(at 0.48 0 180)
			(size 0.59 0.64)
			(layers "F.Cu" "F.Mask" "F.Paste")
			(roundrect_rratio 0.25)
			(net 211 "DDR3_VREF")
			(pintype "passive")
		)
	)
	(footprint "antmicro-footprints:TP_SMD_1mm"
		(layer "F.Cu")
		(at 142.575 163.275)
		(property "Reference" "TP12"
			(at 0.525 0.325 0)
			(layer "F.SilkS")
			(effects
				(font
					(size 0.7 0.7)
					(thickness 0.15)
				)
				(justify left bottom)
			)
		)
		(property "Value" "TP_1mm_SMD"
			(at 0 1.4 0)
			(layer "F.Fab")
			(effects
				(font
					(size 0.7 0.7)
					(thickness 0.15)
				)
				(justify left bottom)
			)
		)
		(property "Description" "Test point 1mm SMD"
			(at 0 0 0)
			(layer "F.Fab")
			(hide yes)
			(effects
				(font
					(size 1.27 1.27)
					(thickness 0.15)
				)
			)
		)
		(property "Author" "Antmicro"
			(at 0 0 0)
			(layer "F.Fab")
			(hide yes)
			(effects
				(font
					(size 1 1)
					(thickness 0.15)
				)
			)
		)
		(property "License" "Apache-2.0"
			(at 0 0 0)
			(layer "F.Fab")
			(hide yes)
			(effects
				(font
					(size 1 1)
					(thickness 0.15)
				)
			)
		)
		(property "MPN" ""
			(at 0 0 0)
			(layer "F.Fab")
			(hide yes)
			(effects
				(font
					(size 1 1)
					(thickness 0.15)
				)
			)
		)
		(property "Manufacturer" ""
			(at 0 0 0)
			(layer "F.Fab")
			(hide yes)
			(effects
				(font
					(size 1 1)
					(thickness 0.15)
				)
			)
		)
		(sheetname "/PCIe-connector/")
		(sheetfile "pcie-conn.kicad_sch")
		(attr exclude_from_pos_files exclude_from_bom)
		(fp_circle
			(center 0 0)
			(end 0.6 0)
			(stroke
				(width 0.05)
				(type default)
			)
			(fill no)
			(layer "F.CrtYd")
		)
		(pad "1" smd circle
			(at 0 0)
			(size 1 1)
			(layers "F.Cu" "F.Mask")
			(net 270 "Net-(J2-~{PEWAKE})")
			(pinfunction "1")
			(pintype "passive")
		)
	)
)
